(kicad_pcb
	(version 20260206)
	(generator "pcbnew")
	(generator_version "10.0")
	(general
		(thickness 1.6)
		(legacy_teardrops no)
	)
	(paper "A4")
	(title_block
		(title "12092022_DA0F0TFB6D0_F0T_FAN_BOARD_MP5048_D_brd_v02_OCP.brd")
		(comment 1 "Grand Teton / footprints 894-896 of 924")
	)
	(layers
		(0 "F.Cu" signal "TOP")
		(4 "In1.Cu" signal "GND")
		(6 "In2.Cu" signal "IN1")
		(8 "In3.Cu" signal "IN2")
		(10 "In4.Cu" signal "GND1")
		(2 "B.Cu" signal "BOTTOM")
		(9 "F.Adhes" user "F.Adhesive")
		(11 "B.Adhes" user "B.Adhesive")
		(13 "F.Paste" user "Package Geometry/Pastemask Top")
		(15 "B.Paste" user "Package Geometry/Pastemask Bottom")
		(5 "F.SilkS" user "Ref Des/Silkscreen Top")
		(7 "B.SilkS" user "Ref Des/Silkscreen Bottom")
		(1 "F.Mask" user "Board Geometry/Soldermask Top")
		(3 "B.Mask" user "Board Geometry/Soldermask Bottom")
		(17 "Dwgs.User" user "User.Drawings")
		(19 "Cmts.User" user "User.Comments")
		(21 "Eco1.User" user "User.Eco1")
		(23 "Eco2.User" user "User.Eco2")
		(25 "Edge.Cuts" user "Board Geometry/Outline")
		(27 "Margin" user)
		(31 "F.CrtYd" user "Package Geometry/Place Bound Top")
		(29 "B.CrtYd" user "Package Geometry/Place Bound Bottom")
		(35 "F.Fab" user "Ref Des/Assembly Top")
		(33 "B.Fab" user "Ref Des/Assembly Bottom")
	)
	(footprint ""
		(layer "B.Cu")
		(at 34.925 -86.106)
		(property "Reference" "PC30"
			(at 0 0 0)
			(layer "B.SilkS")
			(hide yes)
			(effects
				(font
					(size 1.27 1.27)
				)
				(justify mirror)
			)
		)
		(property "Value" ""
			(at 0 0 0)
			(layer "B.Fab")
			(effects
				(font
					(size 1.27 1.27)
				)
				(justify mirror)
			)
		)
		(duplicate_pad_numbers_are_jumpers no)
		(fp_line
			(start -1.524 -0.762)
			(end -1.524 0.762)
			(stroke
				(width 0.1524)
				(type default)
			)
			(layer "B.SilkS")
		)
		(fp_line
			(start -1.524 0.762)
			(end 1.524 0.762)
			(stroke
				(width 0.1524)
				(type default)
			)
			(layer "B.SilkS")
		)
		(fp_line
			(start 1.524 -0.762)
			(end -1.524 -0.762)
			(stroke
				(width 0.1524)
				(type default)
			)
			(layer "B.SilkS")
		)
		(fp_line
			(start 1.524 0.762)
			(end 1.524 -0.762)
			(stroke
				(width 0.1524)
				(type default)
			)
			(layer "B.SilkS")
		)
		(fp_line
			(start -1.1049 -0.724916)
			(end 1.1049 -0.724916)
			(stroke
				(width 0.1)
				(type default)
			)
			(layer "B.Fab")
		)
		(fp_line
			(start -1.1049 0.724916)
			(end -1.1049 -0.724916)
			(stroke
				(width 0.1)
				(type default)
			)
			(layer "B.Fab")
		)
		(fp_line
			(start 1.1049 -0.724916)
			(end 1.1049 0.724916)
			(stroke
				(width 0.1)
				(type default)
			)
			(layer "B.Fab")
		)
		(fp_line
			(start 1.1049 0.724916)
			(end -1.1049 0.724916)
			(stroke
				(width 0.1)
				(type default)
			)
			(layer "B.Fab")
		)
		(pad "1" smd rect
			(at 0.889 0)
			(size 1.016 1.27)
			(layers "B.Cu" "B.Mask" "B.Paste")
			(net "P52V_FAN_2")
		)
		(pad "2" smd rect
			(at -0.889 0)
			(size 1.016 1.27)
			(layers "B.Cu" "B.Mask" "B.Paste")
			(net "GND")
		)
	)
	(footprint ""
		(layer "B.Cu")
		(at 14.255242 -79.804768 180)
		(property "Reference" "PU7"
			(at -6.064758 -2.234438 0)
			(unlocked yes)
			(layer "B.SilkS")
			(effects
				(font
					(size 0.7874 0.5842)
					(thickness 0.1524)
				)
				(justify left mirror)
			)
		)
		(property "Value" ""
			(at 0 0 0)
			(layer "B.Fab")
			(effects
				(font
					(size 1.27 1.27)
				)
				(justify mirror)
			)
		)
		(duplicate_pad_numbers_are_jumpers no)
		(fp_line
			(start 2.549906 2.549906)
			(end 2.4384 2.549906)
			(stroke
				(width 0.1524)
				(type default)
			)
			(layer "B.SilkS")
		)
		(fp_line
			(start 2.549906 2.2352)
			(end 2.549906 2.549906)
			(stroke
				(width 0.1524)
				(type default)
			)
			(layer "B.SilkS")
		)
		(fp_line
			(start 2.549906 1.4986)
			(end 2.549906 1.7526)
			(stroke
				(width 0.1524)
				(type default)
			)
			(layer "B.SilkS")
		)
		(fp_line
			(start 2.549906 0.6858)
			(end 2.549906 0.9144)
			(stroke
				(width 0.1524)
				(type default)
			)
			(layer "B.SilkS")
		)
		(fp_line
			(start 2.549906 -0.9144)
			(end 2.549906 0.1016)
			(stroke
				(width 0.1524)
				(type default)
			)
			(layer "B.SilkS")
		)
		(fp_line
			(start 2.549906 -1.7526)
			(end 2.549906 -1.4986)
			(stroke
				(width 0.1524)
				(type default)
			)
			(layer "B.SilkS")
		)
		(fp_line
			(start 2.549906 -2.549906)
			(end 2.549906 -2.2352)
			(stroke
				(width 0.1524)
				(type default)
			)
			(layer "B.SilkS")
		)
		(fp_line
			(start 2.4384 -2.549906)
			(end 2.549906 -2.549906)
			(stroke
				(width 0.1524)
				(type default)
			)
			(layer "B.SilkS")
		)
		(fp_line
			(start 2.199894 -3.9624)
			(end 2.199894 -2.9464)
			(stroke
				(width 0.1524)
				(type default)
			)
			(layer "B.SilkS")
		)
		(fp_line
			(start 1.800098 2.9464)
			(end 1.800098 3.4544)
			(stroke
				(width 0.1524)
				(type default)
			)
			(layer "B.SilkS")
		)
		(fp_line
			(start 0.199898 -3.4544)
			(end 0.199898 -2.9464)
			(stroke
				(width 0.1524)
				(type default)
			)
			(layer "B.SilkS")
		)
		(fp_line
			(start -0.199898 2.9464)
			(end -0.199898 3.9624)
			(stroke
				(width 0.1524)
				(type default)
			)
			(layer "B.SilkS")
		)
		(fp_line
			(start -1.800098 -3.9624)
			(end -1.800098 -2.9464)
			(stroke
				(width 0.1524)
				(type default)
			)
			(layer "B.SilkS")
		)
		(fp_line
			(start -2.199894 2.9464)
			(end -2.199894 3.4544)
			(stroke
				(width 0.1524)
				(type default)
			)
			(layer "B.SilkS")
		)
		(fp_line
			(start -2.4384 2.549906)
			(end -2.549906 2.549906)
			(stroke
				(width 0.1524)
				(type default)
			)
			(layer "B.SilkS")
		)
		(fp_line
			(start -2.549906 2.549906)
			(end -2.549906 2.2352)
			(stroke
				(width 0.1524)
				(type default)
			)
			(layer "B.SilkS")
		)
		(fp_line
			(start -2.549906 1.7526)
			(end -2.549906 1.4986)
			(stroke
				(width 0.1524)
				(type default)
			)
			(layer "B.SilkS")
		)
		(fp_line
			(start -2.549906 0.9144)
			(end -2.549906 -0.1016)
			(stroke
				(width 0.1524)
				(type default)
			)
			(layer "B.SilkS")
		)
		(fp_line
			(start -2.549906 -0.6858)
			(end -2.549906 -0.9144)
			(stroke
				(width 0.1524)
				(type default)
			)
			(layer "B.SilkS")
		)
		(fp_line
			(start -2.549906 -1.4986)
			(end -2.549906 -1.7526)
			(stroke
				(width 0.1524)
				(type default)
			)
			(layer "B.SilkS")
		)
		(fp_line
			(start -2.549906 -2.2352)
			(end -2.549906 -2.549906)
			(stroke
				(width 0.1524)
				(type default)
			)
			(layer "B.SilkS")
		)
		(fp_line
			(start -2.549906 -2.549906)
			(end -2.4384 -2.549906)
			(stroke
				(width 0.1524)
				(type default)
			)
			(layer "B.SilkS")
		)
		(fp_poly
			(pts
				(xy 3.587242 -1.524) (xy 2.939034 -1.199896) (xy 3.587242 -0.875792)
			)
			(stroke
				(width 0)
				(type default)
			)
			(fill yes)
			(layer "B.SilkS")
		)
		(fp_line
			(start 2.549906 2.549906)
			(end -2.549906 2.549906)
			(stroke
				(width 0.1)
				(type default)
			)
			(layer "B.Fab")
		)
		(fp_line
			(start 2.549906 -2.549906)
			(end 2.549906 2.549906)
			(stroke
				(width 0.1)
				(type default)
			)
			(layer "B.Fab")
		)
		(fp_line
			(start 2.199894 -3.9624)
			(end 2.199894 -2.9464)
			(stroke
				(width 0.1)
				(type default)
			)
			(layer "B.Fab")
		)
		(fp_line
			(start 1.800098 2.9464)
			(end 1.800098 3.4544)
			(stroke
				(width 0.1)
				(type default)
			)
			(layer "B.Fab")
		)
		(fp_line
			(start 0.199898 -3.4544)
			(end 0.199898 -2.9464)
			(stroke
				(width 0.1)
				(type default)
			)
			(layer "B.Fab")
		)
		(fp_line
			(start -0.199898 2.9464)
			(end -0.199898 3.9624)
			(stroke
				(width 0.1)
				(type default)
			)
			(layer "B.Fab")
		)
		(fp_line
			(start -1.800098 -3.9624)
			(end -1.800098 -2.9464)
			(stroke
				(width 0.1)
				(type default)
			)
			(layer "B.Fab")
		)
		(fp_line
			(start -2.199894 2.9464)
			(end -2.199894 3.4544)
			(stroke
				(width 0.1)
				(type default)
			)
			(layer "B.Fab")
		)
		(fp_line
			(start -2.549906 2.549906)
			(end -2.549906 -2.549906)
			(stroke
				(width 0.1)
				(type default)
			)
			(layer "B.Fab")
		)
		(fp_line
			(start -2.549906 -2.549906)
			(end 2.549906 -2.549906)
			(stroke
				(width 0.1)
				(type default)
			)
			(layer "B.Fab")
		)
		(fp_poly
			(pts
				(xy 3.7084 -1.584706) (xy 2.939034 -1.199896) (xy 3.7084 -0.81534)
			)
			(stroke
				(width 0)
				(type default)
			)
			(fill yes)
			(layer "B.Fab")
		)
		(fp_text user "3"
			(at 3.299968 1.1938 90)
			(unlocked yes)
			(layer "B.SilkS")
			(effects
				(font
					(size 0.635 0.4064)
					(thickness 0.1524)
				)
				(justify mirror)
			)
		)
		(fp_text user "30"
			(at 2.9464 -3.045968 180)
			(unlocked yes)
			(layer "B.SilkS")
			(effects
				(font
					(size 0.635 0.4064)
					(thickness 0.1524)
				)
				(justify mirror)
			)
		)
		(fp_text user "4"
			(at 2.6416 3.151632 180)
			(unlocked yes)
			(layer "B.SilkS")
			(effects
				(font
					(size 0.635 0.4064)
					(thickness 0.1524)
				)
				(justify mirror)
			)
		)
		(fp_text user "19"
			(at -2.8448 -3.096768 180)
			(unlocked yes)
			(layer "B.SilkS")
			(effects
				(font
					(size 0.635 0.4064)
					(thickness 0.1524)
				)
				(justify mirror)
			)
		)
		(fp_text user "15"
			(at -2.8956 3.126232 180)
			(unlocked yes)
			(layer "B.SilkS")
			(effects
				(font
					(size 0.635 0.4064)
					(thickness 0.1524)
				)
				(justify mirror)
			)
		)
		(fp_text user "18"
			(at -3.304032 -1.2192 90)
			(unlocked yes)
			(layer "B.SilkS")
			(effects
				(font
					(size 0.635 0.4064)
					(thickness 0.1524)
				)
				(justify mirror)
			)
		)
		(fp_text user "16"
			(at -3.329432 1.2192 90)
			(unlocked yes)
			(layer "B.SilkS")
			(effects
				(font
					(size 0.635 0.4064)
					(thickness 0.1524)
				)
				(justify mirror)
			)
		)
		(fp_text user "3"
			(at 3.299968 1.1938 90)
			(unlocked yes)
			(layer "B.Fab")
			(effects
				(font
					(size 0.635 0.4064)
					(thickness 0.1524)
				)
				(justify mirror)
			)
		)
		(fp_text user "30"
			(at 2.9464 -3.045968 180)
			(unlocked yes)
			(layer "B.Fab")
			(effects
				(font
					(size 0.635 0.4064)
					(thickness 0.1524)
				)
				(justify mirror)
			)
		)
		(fp_text user "4"
			(at 2.6416 3.151632 180)
			(unlocked yes)
			(layer "B.Fab")
			(effects
				(font
					(size 0.635 0.4064)
					(thickness 0.1524)
				)
				(justify mirror)
			)
		)
		(fp_text user "19"
			(at -2.8448 -3.096768 180)
			(unlocked yes)
			(layer "B.Fab")
			(effects
				(font
					(size 0.635 0.4064)
					(thickness 0.1524)
				)
				(justify mirror)
			)
		)
		(fp_text user "15"
			(at -2.8956 3.126232 180)
			(unlocked yes)
			(layer "B.Fab")
			(effects
				(font
					(size 0.635 0.4064)
					(thickness 0.1524)
				)
				(justify mirror)
			)
		)
		(fp_text user "18"
			(at -3.304032 -1.2192 90)
			(unlocked yes)
			(layer "B.Fab")
			(effects
				(font
					(size 0.635 0.4064)
					(thickness 0.1524)
				)
				(justify mirror)
			)
		)
		(fp_text user "16"
			(at -3.329432 1.2192 90)
			(unlocked yes)
			(layer "B.Fab")
			(effects
				(font
					(size 0.635 0.4064)
					(thickness 0.1524)
				)
				(justify mirror)
			)
		)
		(pad "1" smd circle
			(at 1.599946 -1.199896 90)
			(size 0 0)
			(layers "B.Cu" "B.Mask" "B.Paste")
			(net "P52V_HSC")
		)
		(pad "2" smd rect
			(at 1.549908 0.40005 270)
			(size 0.3048 2.5146)
			(layers "B.Cu" "B.Mask" "B.Paste")
			(net "P52V_HSC")
		)
		(pad "3" smd rect
			(at 1.549908 1.199896 270)
			(size 0.3048 2.5146)
			(layers "B.Cu" "B.Mask" "B.Paste")
			(net "P52V_FAN_5")
		)
		(pad "4" smd circle
			(at 2.199894 2.350008 180)
			(size 0 0)
			(layers "B.Cu" "B.Mask" "B.Paste")
			(net "P52V_FAN_5")
		)
		(pad "5" smd rect
			(at 1.800098 2.350008)
			(size 0.1778 0.9144)
			(layers "B.Cu" "B.Mask" "B.Paste")
			(net "P52V_FAN_5")
		)
		(pad "6" smd rect
			(at 1.400048 2.350008)
			(size 0.1778 0.9144)
			(layers "B.Cu" "B.Mask" "B.Paste")
			(net "P52V_FAN_5")
		)
		(pad "7" smd rect
			(at 0.999998 2.350008)
			(size 0.1778 0.9144)
			(layers "B.Cu" "B.Mask" "B.Paste")
			(net "P52V_FAN_5")
		)
		(pad "8" smd rect
			(at 0.599948 2.350008)
			(size 0.1778 0.9144)
			(layers "B.Cu" "B.Mask" "B.Paste")
			(net "P52V_FAN_5")
		)
		(pad "9" smd rect
			(at 0.199898 2.350008)
			(size 0.1778 0.9144)
			(layers "B.Cu" "B.Mask" "B.Paste")
			(net "P52V_FAN_5")
		)
		(pad "10" smd rect
			(at -0.199898 2.350008)
			(size 0.1778 0.9144)
			(layers "B.Cu" "B.Mask" "B.Paste")
			(net "P52V_FAN_5")
		)
		(pad "11" smd rect
			(at -0.599948 2.350008)
			(size 0.1778 0.9144)
			(layers "B.Cu" "B.Mask" "B.Paste")
			(net "P52V_FAN_5")
		)
		(pad "12" smd rect
			(at -0.999998 2.350008)
			(size 0.1778 0.9144)
			(layers "B.Cu" "B.Mask" "B.Paste")
			(net "P52V_FAN_5")
		)
		(pad "13" smd rect
			(at -1.400048 2.350008)
			(size 0.1778 0.9144)
			(layers "B.Cu" "B.Mask" "B.Paste")
			(net "P52V_FAN_5")
		)
		(pad "14" smd rect
			(at -1.800098 2.350008)
			(size 0.1778 0.9144)
			(layers "B.Cu" "B.Mask" "B.Paste")
			(net "P52V_FAN_5")
		)
		(pad "15" smd circle
			(at -2.199894 2.350008 180)
			(size 0 0)
			(layers "B.Cu" "B.Mask" "B.Paste")
			(net "P52V_FAN_5")
		)
		(pad "16" smd rect
			(at -1.549908 1.199896 270)
			(size 0.3048 2.5146)
			(layers "B.Cu" "B.Mask" "B.Paste")
			(net "P52V_FAN_5")
		)
		(pad "17" smd rect
			(at -1.549908 -0.40005 270)
			(size 0.3048 2.5146)
			(layers "B.Cu" "B.Mask" "B.Paste")
			(net "P52V_FAN_5")
		)
		(pad "18" smd rect
			(at -1.549908 -1.199896 270)
			(size 0.3048 2.5146)
			(layers "B.Cu" "B.Mask" "B.Paste")
			(net "P52V_HSC")
		)
		(pad "19" smd circle
			(at -2.199894 -2.350008)
			(size 0 0)
			(layers "B.Cu" "B.Mask" "B.Paste")
			(net "FAN_5_CS")
		)
		(pad "20" smd rect
			(at -1.800098 -2.350008)
			(size 0.1778 0.9144)
			(layers "B.Cu" "B.Mask" "B.Paste")
			(net "FAN_5_IMON")
		)
		(pad "21" smd rect
			(at -1.400048 -2.350008)
			(size 0.1778 0.9144)
			(layers "B.Cu" "B.Mask" "B.Paste")
			(net "FAN_5_SS")
		)
		(pad "22" smd rect
			(at -0.999998 -2.350008)
			(size 0.1778 0.9144)
			(layers "B.Cu" "B.Mask" "B.Paste")
			(net "FAN_5_FAULT")
		)
		(pad "23" smd rect
			(at -0.599948 -2.350008)
			(size 0.1778 0.9144)
			(layers "B.Cu" "B.Mask" "B.Paste")
			(net "FAN_5_TIMER")
		)
		(pad "24" smd rect
			(at -0.199898 -2.350008)
			(size 0.1778 0.9144)
			(layers "B.Cu" "B.Mask" "B.Paste")
			(net "FAN_5_CLREF")
		)
		(pad "25" smd rect
			(at 0.199898 -2.350008)
			(size 0.1778 0.9144)
			(layers "B.Cu" "B.Mask" "B.Paste")
			(net "GND")
		)
		(pad "26" smd rect
			(at 0.599948 -2.350008)
			(size 0.1778 0.9144)
			(layers "B.Cu" "B.Mask" "B.Paste")
			(net "FAN_5_ON")
		)
		(pad "27" smd rect
			(at 0.999998 -2.350008)
			(size 0.1778 0.9144)
			(layers "B.Cu" "B.Mask" "B.Paste")
			(net "FAN_5_P3V_R")
		)
		(pad "28" smd rect
			(at 1.400048 -2.350008)
			(size 0.1778 0.9144)
			(layers "B.Cu" "B.Mask" "B.Paste")
			(net "FAN_5_P5V")
		)
		(pad "29" smd rect
			(at 1.800098 -2.350008)
			(size 0.1778 0.9144)
			(layers "B.Cu" "B.Mask" "B.Paste")
			(net "FAN_5_TEMP")
		)
		(pad "30" smd circle
			(at 2.199894 -2.350008)
			(size 0 0)
			(layers "B.Cu" "B.Mask" "B.Paste")
			(net "FAN_5_MODE")
		)
	)
	(footprint ""
		(layer "B.Cu")
		(at 39.968932 -255.905)
		(property "Reference" "U377"
			(at -3.824732 -0.81153 0)
			(unlocked yes)
			(layer "B.SilkS")
			(effects
				(font
					(size 0.7874 0.5842)
					(thickness 0.1524)
				)
				(justify mirror)
			)
		)
		(property "Value" ""
			(at 0 0 0)
			(layer "B.Fab")
			(effects
				(font
					(size 1.27 1.27)
				)
				(justify mirror)
			)
		)
		(duplicate_pad_numbers_are_jumpers no)
		(fp_line
			(start -1.7018 -1.1176)
			(end -1.7018 1.1176)
			(stroke
				(width 0.1524)
				(type default)
			)
			(layer "B.SilkS")
		)
		(fp_line
			(start -1.7018 -1.1176)
			(end -0.254 -1.1176)
			(stroke
				(width 0.1524)
				(type default)
			)
			(layer "B.SilkS")
		)
		(fp_line
			(start -1.7018 1.1176)
			(end 1.7018 1.1176)
			(stroke
				(width 0.1524)
				(type default)
			)
			(layer "B.SilkS")
		)
		(fp_line
			(start -0.254 -1.1176)
			(end 0 -0.7112)
			(stroke
				(width 0.1524)
				(type default)
			)
			(layer "B.SilkS")
		)
		(fp_line
			(start 0 -0.7112)
			(end 0.254 -1.1176)
			(stroke
				(width 0.1524)
				(type default)
			)
			(layer "B.SilkS")
		)
		(fp_line
			(start 0.254 -1.1176)
			(end 1.7018 -1.1176)
			(stroke
				(width 0.1524)
				(type default)
			)
			(layer "B.SilkS")
		)
		(fp_line
			(start 1.7018 1.1176)
			(end 1.7018 -1.1176)
			(stroke
				(width 0.1524)
				(type default)
			)
			(layer "B.SilkS")
		)
		(fp_poly
			(pts
				(xy 1.8161 -0.675386) (xy 2.4003 -0.446786) (xy 2.4003 -0.878586)
			)
			(stroke
				(width 0)
				(type default)
			)
			(fill yes)
			(layer "B.SilkS")
		)
		(fp_line
			(start -1.5494 -1.1176)
			(end -1.5494 1.1176)
			(stroke
				(width 0.1)
				(type default)
			)
			(layer "B.Fab")
		)
		(fp_line
			(start -1.5494 -1.1176)
			(end -0.254 -1.1176)
			(stroke
				(width 0.1)
				(type default)
			)
			(layer "B.Fab")
		)
		(fp_line
			(start -1.5494 1.1176)
			(end 1.5494 1.1176)
			(stroke
				(width 0.1)
				(type default)
			)
			(layer "B.Fab")
		)
		(fp_line
			(start -0.254 -1.1176)
			(end 0.254 -1.1176)
			(stroke
				(width 0.1)
				(type default)
			)
			(layer "B.Fab")
		)
		(fp_line
			(start 0.254 -1.1176)
			(end 1.5494 -1.1176)
			(stroke
				(width 0.1)
				(type default)
			)
			(layer "B.Fab")
		)
		(fp_line
			(start 1.5494 1.1176)
			(end 1.5494 -1.1176)
			(stroke
				(width 0.1)
				(type default)
			)
			(layer "B.Fab")
		)
		(fp_poly
			(pts
				(xy 1.8161 -0.675386) (xy 2.4003 -0.446786) (xy 2.4003 -0.878586)
			)
			(stroke
				(width 0)
				(type default)
			)
			(fill yes)
			(layer "B.Fab")
		)
		(pad "1" smd rect
			(at 0.962406 -0.649986 270)
			(size 0.3302 1.1684)
			(layers "B.Cu" "B.Mask" "B.Paste")
			(net "FAN_0_PRESENT_R")
		)
		(pad "2" smd rect
			(at 0.962406 0 270)
			(size 0.3302 1.1684)
			(layers "B.Cu" "B.Mask" "B.Paste")
			(net "P52V_FAN_0_BUFF_EN_R")
		)
		(pad "3" smd rect
			(at 0.962406 0.649986 270)
			(size 0.3302 1.1684)
			(layers "B.Cu" "B.Mask" "B.Paste")
			(net "GND")
		)
		(pad "4" smd rect
			(at -0.962406 0.649986 270)
			(size 0.3302 1.1684)
			(layers "B.Cu" "B.Mask" "B.Paste")
			(net "P52V_FAN_0_EN")
		)
		(pad "5" smd rect
			(at -0.962406 -0.649986 270)
			(size 0.3302 1.1684)
			(layers "B.Cu" "B.Mask" "B.Paste")
			(net "P3V3_AUX")
		)
	)
)
